# T6G (Grand Teton) — schematic netlist excerpt (pin names and nets, part order shuffled) for the footprints in the layout excerpt that follows; sources: Cadence DE-HDL packaged netlist, KiCad conversion of 04192023_DAF0TMB3IC0_F0TG_MB_C_brd_V02_OCP.brd

R457  Q_RES  4.7K 5% EMPTY  pkg 0402LF  page 29 : A = PVDD18_S5_P0 ; B = RST_ESPI_CPU0_RSTOUT_N
R1229  Q_RES  18K 1% CHIP  pkg 0402LF  page 258 : A = P1V8_AUX_ADC ; B = GND

(kicad_pcb
	(version 20260206)
	(generator "pcbnew")
	(generator_version "10.0")
	(general
		(thickness 1.6)
		(legacy_teardrops no)
	)
	(paper "A4")
	(title_block
		(title "04192023_DAF0TMB3IC0_F0TG_MB_C_brd_V02_OCP.brd")
		(comment 1 "Grand Teton / footprints 8347-8348 of 8354")
	)
	(layers
		(0 "F.Cu" signal "TOP")
		(4 "In1.Cu" signal "GND")
		(6 "In2.Cu" signal "IN1")
		(8 "In3.Cu" signal "GND1")
		(10 "In4.Cu" signal "IN2")
		(12 "In5.Cu" signal "GND2")
		(14 "In6.Cu" signal "IN3")
		(16 "In7.Cu" signal "GND3")
		(18 "In8.Cu" signal "VCC")
		(20 "In9.Cu" signal "VCC1")
		(22 "In10.Cu" signal "GND4")
		(24 "In11.Cu" signal "IN4")
		(26 "In12.Cu" signal "GND5")
		(28 "In13.Cu" signal "IN5")
		(30 "In14.Cu" signal "GND6")
		(32 "In15.Cu" signal "IN6")
		(34 "In16.Cu" signal "GND7")
		(2 "B.Cu" signal "BOTTOM")
		(9 "F.Adhes" user "F.Adhesive")
		(11 "B.Adhes" user "B.Adhesive")
		(13 "F.Paste" user "Package Geometry/Pastemask Top")
		(15 "B.Paste" user "Package Geometry/Pastemask Bottom")
		(5 "F.SilkS" user "Ref Des/Silkscreen Top")
		(7 "B.SilkS" user "Ref Des/Silkscreen Bottom")
		(1 "F.Mask" user "Board Geometry/Soldermask Top")
		(3 "B.Mask" user "Board Geometry/Soldermask Bottom")
		(17 "Dwgs.User" user "User.Drawings")
		(19 "Cmts.User" user "User.Comments")
		(21 "Eco1.User" user "User.Eco1")
		(23 "Eco2.User" user "User.Eco2")
		(25 "Edge.Cuts" user "Board Geometry/Outline")
		(27 "Margin" user)
		(31 "F.CrtYd" user "Package Geometry/Place Bound Top")
		(29 "B.CrtYd" user "Package Geometry/Place Bound Bottom")
		(35 "F.Fab" user "Ref Des/Assembly Top")
		(33 "B.Fab" user "Ref Des/Assembly Bottom")
	)
	(footprint ""
		(layer "B.Cu")
		(at 400.812508 -330.090272)
		(property "Reference" "R457"
			(at 0 0 0)
			(layer "B.SilkS")
			(hide yes)
			(effects
				(font
					(size 1.27 1.27)
				)
				(justify mirror)
			)
		)
		(property "Value" ""
			(at 0 0 0)
			(layer "B.Fab")
			(effects
				(font
					(size 1.27 1.27)
				)
				(justify mirror)
			)
		)
		(duplicate_pad_numbers_are_jumpers no)
		(fp_line
			(start -0.7874 -0.4064)
			(end -0.7874 0.4064)
			(stroke
				(width 0.1524)
				(type default)
			)
			(layer "B.SilkS")
		)
		(fp_line
			(start -0.7874 0.4064)
			(end 0.7874 0.4064)
			(stroke
				(width 0.1524)
				(type default)
			)
			(layer "B.SilkS")
		)
		(fp_line
			(start 0.7874 -0.4064)
			(end -0.7874 -0.4064)
			(stroke
				(width 0.1524)
				(type default)
			)
			(layer "B.SilkS")
		)
		(fp_line
			(start 0.7874 0.4064)
			(end 0.7874 -0.4064)
			(stroke
				(width 0.1524)
				(type default)
			)
			(layer "B.SilkS")
		)
		(fp_line
			(start -0.67945 -0.3048)
			(end -0.67945 0.3048)
			(stroke
				(width 0.1)
				(type default)
			)
			(layer "B.Fab")
		)
		(fp_line
			(start -0.67945 0.3048)
			(end -0.120396 0.3048)
			(stroke
				(width 0.1)
				(type default)
			)
			(layer "B.Fab")
		)
		(fp_line
			(start -0.12065 -0.3048)
			(end -0.67945 -0.3048)
			(stroke
				(width 0.1)
				(type default)
			)
			(layer "B.Fab")
		)
		(fp_line
			(start -0.12065 -0.2794)
			(end -0.12065 -0.3048)
			(stroke
				(width 0.1)
				(type default)
			)
			(layer "B.Fab")
		)
		(fp_line
			(start -0.120396 0.2794)
			(end 0.12065 0.2794)
			(stroke
				(width 0.1)
				(type default)
			)
			(layer "B.Fab")
		)
		(fp_line
			(start -0.120396 0.3048)
			(end -0.120396 0.2794)
			(stroke
				(width 0.1)
				(type default)
			)
			(layer "B.Fab")
		)
		(fp_line
			(start 0.12065 -0.305054)
			(end 0.12065 -0.2794)
			(stroke
				(width 0.1)
				(type default)
			)
			(layer "B.Fab")
		)
		(fp_line
			(start 0.12065 -0.2794)
			(end -0.12065 -0.2794)
			(stroke
				(width 0.1)
				(type default)
			)
			(layer "B.Fab")
		)
		(fp_line
			(start 0.12065 0.2794)
			(end 0.12065 0.3048)
			(stroke
				(width 0.1)
				(type default)
			)
			(layer "B.Fab")
		)
		(fp_line
			(start 0.12065 0.3048)
			(end 0.67945 0.3048)
			(stroke
				(width 0.1)
				(type default)
			)
			(layer "B.Fab")
		)
		(fp_line
			(start 0.67945 -0.305054)
			(end 0.12065 -0.305054)
			(stroke
				(width 0.1)
				(type default)
			)
			(layer "B.Fab")
		)
		(fp_line
			(start 0.67945 0.3048)
			(end 0.67945 -0.305054)
			(stroke
				(width 0.1)
				(type default)
			)
			(layer "B.Fab")
		)
		(pad "1" smd circle
			(at 0.40005 0 180)
			(size 0 0)
			(layers "B.Cu" "B.Mask" "B.Paste")
			(net "PVDD18_S5_P0")
		)
		(pad "2" smd circle
			(at -0.40005 0 180)
			(size 0 0)
			(layers "B.Cu" "B.Mask" "B.Paste")
			(net "RST_ESPI_CPU0_RSTOUT_N")
		)
	)
	(footprint ""
		(layer "B.Cu")
		(at 234.824016 -322.683632 180)
		(property "Reference" "R1229"
			(at 0 0 0)
			(layer "B.SilkS")
			(hide yes)
			(effects
				(font
					(size 1.27 1.27)
				)
				(justify mirror)
			)
		)
		(property "Value" ""
			(at 0 0 0)
			(layer "B.Fab")
			(effects
				(font
					(size 1.27 1.27)
				)
				(justify mirror)
			)
		)
		(duplicate_pad_numbers_are_jumpers no)
		(fp_line
			(start 0.7874 0.4064)
			(end 0.7874 -0.4064)
			(stroke
				(width 0.1524)
				(type default)
			)
			(layer "B.SilkS")
		)
		(fp_line
			(start 0.7874 -0.4064)
			(end -0.7874 -0.4064)
			(stroke
				(width 0.1524)
				(type default)
			)
			(layer "B.SilkS")
		)
		(fp_line
			(start -0.7874 0.4064)
			(end 0.7874 0.4064)
			(stroke
				(width 0.1524)
				(type default)
			)
			(layer "B.SilkS")
		)
		(fp_line
			(start -0.7874 -0.4064)
			(end -0.7874 0.4064)
			(stroke
				(width 0.1524)
				(type default)
			)
			(layer "B.SilkS")
		)
		(fp_line
			(start 0.67945 0.3048)
			(end 0.67945 -0.305054)
			(stroke
				(width 0.1)
				(type default)
			)
			(layer "B.Fab")
		)
		(fp_line
			(start 0.67945 -0.305054)
			(end 0.12065 -0.305054)
			(stroke
				(width 0.1)
				(type default)
			)
			(layer "B.Fab")
		)
		(fp_line
			(start 0.12065 0.3048)
			(end 0.67945 0.3048)
			(stroke
				(width 0.1)
				(type default)
			)
			(layer "B.Fab")
		)
		(fp_line
			(start 0.12065 0.2794)
			(end 0.12065 0.3048)
			(stroke
				(width 0.1)
				(type default)
			)
			(layer "B.Fab")
		)
		(fp_line
			(start 0.12065 -0.2794)
			(end -0.12065 -0.2794)
			(stroke
				(width 0.1)
				(type default)
			)
			(layer "B.Fab")
		)
		(fp_line
			(start 0.12065 -0.305054)
			(end 0.12065 -0.2794)
			(stroke
				(width 0.1)
				(type default)
			)
			(layer "B.Fab")
		)
		(fp_line
			(start -0.120396 0.3048)
			(end -0.120396 0.2794)
			(stroke
				(width 0.1)
				(type default)
			)
			(layer "B.Fab")
		)
		(fp_line
			(start -0.120396 0.2794)
			(end 0.12065 0.2794)
			(stroke
				(width 0.1)
				(type default)
			)
			(layer "B.Fab")
		)
		(fp_line
			(start -0.12065 -0.2794)
			(end -0.12065 -0.3048)
			(stroke
				(width 0.1)
				(type default)
			)
			(layer "B.Fab")
		)
		(fp_line
			(start -0.12065 -0.3048)
			(end -0.67945 -0.3048)
			(stroke
				(width 0.1)
				(type default)
			)
			(layer "B.Fab")
		)
		(fp_line
			(start -0.67945 0.3048)
			(end -0.120396 0.3048)
			(stroke
				(width 0.1)
				(type default)
			)
			(layer "B.Fab")
		)
		(fp_line
			(start -0.67945 -0.3048)
			(end -0.67945 0.3048)
			(stroke
				(width 0.1)
				(type default)
			)
			(layer "B.Fab")
		)
		(pad "1" smd circle
			(at 0.40005 0)
			(size 0 0)
			(layers "B.Cu" "B.Mask" "B.Paste")
			(net "P1V8_AUX_ADC")
		)
		(pad "2" smd circle
			(at -0.40005 0)
			(size 0 0)
			(layers "B.Cu" "B.Mask" "B.Paste")
			(net "GND")
		)
	)
)
